# SCM (Grand Teton) — schematic netlist excerpt (pin names and nets, part order shuffled) for the footprints in the layout excerpt that follows; sources: Cadence DE-HDL packaged netlist, KiCad conversion of 12092022_DA0F0TMDCD0_F0T_Management_Board_D_brd_V3_OCP.brd

R32  Q_RES  4.7K 1% CHIP  pkg 0402LF  page 23 : A = P3V3_RGM ; B = V_BMC_DDC_SCL
R72  Q_RES  4.7K 1% CHIP  pkg 0402LF  page 30 : A = P3V3_AUX ; B = UART_BMC_5_RXD_BUF1

(kicad_pcb
	(version 20260206)
	(generator "pcbnew")
	(generator_version "10.0")
	(general
		(thickness 1.6)
		(legacy_teardrops no)
	)
	(paper "A4")
	(title_block
		(title "12092022_DA0F0TMDCD0_F0T_Management_Board_D_brd_V3_OCP.brd")
		(comment 1 "Grand Teton / footprints 103-104 of 1440")
	)
	(layers
		(0 "F.Cu" signal "TOP")
		(4 "In1.Cu" signal "GND")
		(6 "In2.Cu" signal "IN1")
		(8 "In3.Cu" signal "GND1")
		(10 "In4.Cu" signal "IN2")
		(12 "In5.Cu" signal "VCC")
		(14 "In6.Cu" signal "VCC1")
		(16 "In7.Cu" signal "IN3")
		(18 "In8.Cu" signal "GND2")
		(20 "In9.Cu" signal "IN4")
		(22 "In10.Cu" signal "GND3")
		(2 "B.Cu" signal "BOTTOM")
		(9 "F.Adhes" user "F.Adhesive")
		(11 "B.Adhes" user "B.Adhesive")
		(13 "F.Paste" user "Package Geometry/Pastemask Top")
		(15 "B.Paste" user "Package Geometry/Pastemask Bottom")
		(5 "F.SilkS" user "Ref Des/Silkscreen Top")
		(7 "B.SilkS" user "Ref Des/Silkscreen Bottom")
		(1 "F.Mask" user "Board Geometry/Soldermask Top")
		(3 "B.Mask" user "Board Geometry/Soldermask Bottom")
		(17 "Dwgs.User" user "User.Drawings")
		(19 "Cmts.User" user "User.Comments")
		(21 "Eco1.User" user "User.Eco1")
		(23 "Eco2.User" user "User.Eco2")
		(25 "Edge.Cuts" user "Board Geometry/Outline")
		(27 "Margin" user)
		(31 "F.CrtYd" user "Package Geometry/Place Bound Top")
		(29 "B.CrtYd" user "Package Geometry/Place Bound Bottom")
		(35 "F.Fab" user "Ref Des/Assembly Top")
		(33 "B.Fab" user "Ref Des/Assembly Bottom")
	)
	(footprint ""
		(layer "F.Cu")
		(at 26.924 -20.32)
		(property "Reference" "R32"
			(at 0 0 0)
			(layer "F.SilkS")
			(hide yes)
			(effects
				(font
					(size 1.27 1.27)
				)
			)
		)
		(property "Value" ""
			(at 0 0 0)
			(layer "F.Fab")
			(effects
				(font
					(size 1.27 1.27)
				)
			)
		)
		(duplicate_pad_numbers_are_jumpers no)
		(fp_line
			(start -0.7874 -0.4064)
			(end 0.7874 -0.4064)
			(stroke
				(width 0.1524)
				(type default)
			)
			(layer "F.SilkS")
		)
		(fp_line
			(start -0.7874 0.4064)
			(end -0.7874 -0.4064)
			(stroke
				(width 0.1524)
				(type default)
			)
			(layer "F.SilkS")
		)
		(fp_line
			(start 0.7874 -0.4064)
			(end 0.7874 0.4064)
			(stroke
				(width 0.1524)
				(type default)
			)
			(layer "F.SilkS")
		)
		(fp_line
			(start 0.7874 0.4064)
			(end -0.7874 0.4064)
			(stroke
				(width 0.1524)
				(type default)
			)
			(layer "F.SilkS")
		)
		(fp_line
			(start -0.67945 -0.305054)
			(end -0.12065 -0.305054)
			(stroke
				(width 0.1)
				(type default)
			)
			(layer "F.Fab")
		)
		(fp_line
			(start -0.67945 0.3048)
			(end -0.67945 -0.305054)
			(stroke
				(width 0.1)
				(type default)
			)
			(layer "F.Fab")
		)
		(fp_line
			(start -0.12065 -0.305054)
			(end -0.12065 -0.2794)
			(stroke
				(width 0.1)
				(type default)
			)
			(layer "F.Fab")
		)
		(fp_line
			(start -0.12065 -0.2794)
			(end 0.12065 -0.2794)
			(stroke
				(width 0.1)
				(type default)
			)
			(layer "F.Fab")
		)
		(fp_line
			(start -0.12065 0.2794)
			(end -0.12065 0.3048)
			(stroke
				(width 0.1)
				(type default)
			)
			(layer "F.Fab")
		)
		(fp_line
			(start -0.12065 0.3048)
			(end -0.67945 0.3048)
			(stroke
				(width 0.1)
				(type default)
			)
			(layer "F.Fab")
		)
		(fp_line
			(start 0.120396 0.2794)
			(end -0.12065 0.2794)
			(stroke
				(width 0.1)
				(type default)
			)
			(layer "F.Fab")
		)
		(fp_line
			(start 0.120396 0.3048)
			(end 0.120396 0.2794)
			(stroke
				(width 0.1)
				(type default)
			)
			(layer "F.Fab")
		)
		(fp_line
			(start 0.12065 -0.3048)
			(end 0.67945 -0.3048)
			(stroke
				(width 0.1)
				(type default)
			)
			(layer "F.Fab")
		)
		(fp_line
			(start 0.12065 -0.2794)
			(end 0.12065 -0.3048)
			(stroke
				(width 0.1)
				(type default)
			)
			(layer "F.Fab")
		)
		(fp_line
			(start 0.67945 -0.3048)
			(end 0.67945 0.3048)
			(stroke
				(width 0.1)
				(type default)
			)
			(layer "F.Fab")
		)
		(fp_line
			(start 0.67945 0.3048)
			(end 0.120396 0.3048)
			(stroke
				(width 0.1)
				(type default)
			)
			(layer "F.Fab")
		)
		(pad "1" smd circle
			(at -0.40005 0)
			(size 0 0)
			(layers "F.Cu" "F.Mask" "F.Paste")
			(net "P3V3_RGM")
		)
		(pad "2" smd circle
			(at 0.40005 0)
			(size 0 0)
			(layers "F.Cu" "F.Mask" "F.Paste")
			(net "V_BMC_DDC_SCL")
		)
	)
	(footprint ""
		(layer "F.Cu")
		(at 30.564074 -61.341 -90)
		(property "Reference" "R72"
			(at 0 0 270)
			(layer "F.SilkS")
			(hide yes)
			(effects
				(font
					(size 1.27 1.27)
				)
			)
		)
		(property "Value" ""
			(at 0 0 270)
			(layer "F.Fab")
			(effects
				(font
					(size 1.27 1.27)
				)
			)
		)
		(duplicate_pad_numbers_are_jumpers no)
		(fp_line
			(start -0.7874 0.4064)
			(end -0.7874 -0.4064)
			(stroke
				(width 0.1524)
				(type default)
			)
			(layer "F.SilkS")
		)
		(fp_line
			(start 0.7874 0.4064)
			(end -0.7874 0.4064)
			(stroke
				(width 0.1524)
				(type default)
			)
			(layer "F.SilkS")
		)
		(fp_line
			(start -0.7874 -0.4064)
			(end 0.7874 -0.4064)
			(stroke
				(width 0.1524)
				(type default)
			)
			(layer "F.SilkS")
		)
		(fp_line
			(start 0.7874 -0.4064)
			(end 0.7874 0.4064)
			(stroke
				(width 0.1524)
				(type default)
			)
			(layer "F.SilkS")
		)
		(fp_line
			(start -0.67945 0.3048)
			(end -0.67945 -0.305054)
			(stroke
				(width 0.1)
				(type default)
			)
			(layer "F.Fab")
		)
		(fp_line
			(start -0.12065 0.3048)
			(end -0.67945 0.3048)
			(stroke
				(width 0.1)
				(type default)
			)
			(layer "F.Fab")
		)
		(fp_line
			(start 0.120396 0.3048)
			(end 0.120396 0.2794)
			(stroke
				(width 0.1)
				(type default)
			)
			(layer "F.Fab")
		)
		(fp_line
			(start 0.67945 0.3048)
			(end 0.120396 0.3048)
			(stroke
				(width 0.1)
				(type default)
			)
			(layer "F.Fab")
		)
		(fp_line
			(start -0.12065 0.2794)
			(end -0.12065 0.3048)
			(stroke
				(width 0.1)
				(type default)
			)
			(layer "F.Fab")
		)
		(fp_line
			(start 0.120396 0.2794)
			(end -0.12065 0.2794)
			(stroke
				(width 0.1)
				(type default)
			)
			(layer "F.Fab")
		)
		(fp_line
			(start -0.12065 -0.2794)
			(end 0.12065 -0.2794)
			(stroke
				(width 0.1)
				(type default)
			)
			(layer "F.Fab")
		)
		(fp_line
			(start 0.12065 -0.2794)
			(end 0.12065 -0.3048)
			(stroke
				(width 0.1)
				(type default)
			)
			(layer "F.Fab")
		)
		(fp_line
			(start 0.12065 -0.3048)
			(end 0.67945 -0.3048)
			(stroke
				(width 0.1)
				(type default)
			)
			(layer "F.Fab")
		)
		(fp_line
			(start 0.67945 -0.3048)
			(end 0.67945 0.3048)
			(stroke
				(width 0.1)
				(type default)
			)
			(layer "F.Fab")
		)
		(fp_line
			(start -0.67945 -0.305054)
			(end -0.12065 -0.305054)
			(stroke
				(width 0.1)
				(type default)
			)
			(layer "F.Fab")
		)
		(fp_line
			(start -0.12065 -0.305054)
			(end -0.12065 -0.2794)
			(stroke
				(width 0.1)
				(type default)
			)
			(layer "F.Fab")
		)
		(pad "1" smd circle
			(at -0.40005 0 270)
			(size 0 0)
			(layers "F.Cu" "F.Mask" "F.Paste")
			(net "P3V3_AUX")
		)
		(pad "2" smd circle
			(at 0.40005 0 270)
			(size 0 0)
			(layers "F.Cu" "F.Mask" "F.Paste")
			(net "UART_BMC_5_RXD_BUF1")
		)
	)
)
